# T6G (Grand Teton) — schematic netlist excerpt (pin names and nets, part order shuffled) for the footprints in the layout excerpt that follows; sources: Cadence DE-HDL packaged netlist, KiCad conversion of 04192023_DAF0TMB3IC0_F0TG_MB_C_brd_V02_OCP.brd

C35  Q_CAP  100PF 50V 5% EMPTY  pkg 0402  page 257 : A = P12V_E1S_0_ISENSE_MAM ; B = GND
C288  Q_CAP  0.1UF 10V 10% X7S  pkg C0201  page 334 : A = P1V8_CPU1_RT1_1A ; B = GND
C2249  Q_CAP  22UF 4V 20% X6S  pkg C0402  page 69 : A = PVDDCR_CPU1_P0 ; B = GND

(kicad_pcb
	(version 20260206)
	(generator "pcbnew")
	(generator_version "10.0")
	(general
		(thickness 1.6)
		(legacy_teardrops no)
	)
	(paper "A4")
	(title_block
		(title "04192023_DAF0TMB3IC0_F0TG_MB_C_brd_V02_OCP.brd")
		(comment 1 "Grand Teton / footprints 7902-7904 of 8354")
	)
	(layers
		(0 "F.Cu" signal "TOP")
		(4 "In1.Cu" signal "GND")
		(6 "In2.Cu" signal "IN1")
		(8 "In3.Cu" signal "GND1")
		(10 "In4.Cu" signal "IN2")
		(12 "In5.Cu" signal "GND2")
		(14 "In6.Cu" signal "IN3")
		(16 "In7.Cu" signal "GND3")
		(18 "In8.Cu" signal "VCC")
		(20 "In9.Cu" signal "VCC1")
		(22 "In10.Cu" signal "GND4")
		(24 "In11.Cu" signal "IN4")
		(26 "In12.Cu" signal "GND5")
		(28 "In13.Cu" signal "IN5")
		(30 "In14.Cu" signal "GND6")
		(32 "In15.Cu" signal "IN6")
		(34 "In16.Cu" signal "GND7")
		(2 "B.Cu" signal "BOTTOM")
		(9 "F.Adhes" user "F.Adhesive")
		(11 "B.Adhes" user "B.Adhesive")
		(13 "F.Paste" user "Package Geometry/Pastemask Top")
		(15 "B.Paste" user "Package Geometry/Pastemask Bottom")
		(5 "F.SilkS" user "Ref Des/Silkscreen Top")
		(7 "B.SilkS" user "Ref Des/Silkscreen Bottom")
		(1 "F.Mask" user "Board Geometry/Soldermask Top")
		(3 "B.Mask" user "Board Geometry/Soldermask Bottom")
		(17 "Dwgs.User" user "User.Drawings")
		(19 "Cmts.User" user "User.Comments")
		(21 "Eco1.User" user "User.Eco1")
		(23 "Eco2.User" user "User.Eco2")
		(25 "Edge.Cuts" user "Board Geometry/Outline")
		(27 "Margin" user)
		(31 "F.CrtYd" user "Package Geometry/Place Bound Top")
		(29 "B.CrtYd" user "Package Geometry/Place Bound Bottom")
		(35 "F.Fab" user "Ref Des/Assembly Top")
		(33 "B.Fab" user "Ref Des/Assembly Bottom")
	)
	(footprint ""
		(layer "B.Cu")
		(at 328.92365 -34.139886 180)
		(property "Reference" "C35"
			(at 0 0 0)
			(layer "B.SilkS")
			(hide yes)
			(effects
				(font
					(size 1.27 1.27)
				)
				(justify mirror)
			)
		)
		(property "Value" ""
			(at 0 0 0)
			(layer "B.Fab")
			(effects
				(font
					(size 1.27 1.27)
				)
				(justify mirror)
			)
		)
		(duplicate_pad_numbers_are_jumpers no)
		(fp_line
			(start 0.7874 0.4064)
			(end 0.7874 -0.4064)
			(stroke
				(width 0.1524)
				(type default)
			)
			(layer "B.SilkS")
		)
		(fp_line
			(start 0.7874 -0.4064)
			(end -0.7874 -0.4064)
			(stroke
				(width 0.1524)
				(type default)
			)
			(layer "B.SilkS")
		)
		(fp_line
			(start -0.7874 0.4064)
			(end 0.7874 0.4064)
			(stroke
				(width 0.1524)
				(type default)
			)
			(layer "B.SilkS")
		)
		(fp_line
			(start -0.7874 -0.4064)
			(end -0.7874 0.4064)
			(stroke
				(width 0.1524)
				(type default)
			)
			(layer "B.SilkS")
		)
		(fp_line
			(start 0.67945 0.3048)
			(end 0.67945 -0.305054)
			(stroke
				(width 0.1)
				(type default)
			)
			(layer "B.Fab")
		)
		(fp_line
			(start 0.67945 -0.305054)
			(end 0.12065 -0.305054)
			(stroke
				(width 0.1)
				(type default)
			)
			(layer "B.Fab")
		)
		(fp_line
			(start 0.12065 0.3048)
			(end 0.67945 0.3048)
			(stroke
				(width 0.1)
				(type default)
			)
			(layer "B.Fab")
		)
		(fp_line
			(start 0.12065 0.2794)
			(end 0.12065 0.3048)
			(stroke
				(width 0.1)
				(type default)
			)
			(layer "B.Fab")
		)
		(fp_line
			(start 0.12065 -0.2794)
			(end -0.12065 -0.2794)
			(stroke
				(width 0.1)
				(type default)
			)
			(layer "B.Fab")
		)
		(fp_line
			(start 0.12065 -0.305054)
			(end 0.12065 -0.2794)
			(stroke
				(width 0.1)
				(type default)
			)
			(layer "B.Fab")
		)
		(fp_line
			(start -0.120396 0.3048)
			(end -0.120396 0.2794)
			(stroke
				(width 0.1)
				(type default)
			)
			(layer "B.Fab")
		)
		(fp_line
			(start -0.120396 0.2794)
			(end 0.12065 0.2794)
			(stroke
				(width 0.1)
				(type default)
			)
			(layer "B.Fab")
		)
		(fp_line
			(start -0.12065 -0.2794)
			(end -0.12065 -0.3048)
			(stroke
				(width 0.1)
				(type default)
			)
			(layer "B.Fab")
		)
		(fp_line
			(start -0.12065 -0.3048)
			(end -0.67945 -0.3048)
			(stroke
				(width 0.1)
				(type default)
			)
			(layer "B.Fab")
		)
		(fp_line
			(start -0.67945 0.3048)
			(end -0.120396 0.3048)
			(stroke
				(width 0.1)
				(type default)
			)
			(layer "B.Fab")
		)
		(fp_line
			(start -0.67945 -0.3048)
			(end -0.67945 0.3048)
			(stroke
				(width 0.1)
				(type default)
			)
			(layer "B.Fab")
		)
		(pad "1" smd circle
			(at 0.40005 0)
			(size 0 0)
			(layers "B.Cu" "B.Mask" "B.Paste")
			(net "P12V_E1S_0_ISENSE_MAM")
		)
		(pad "2" smd circle
			(at -0.40005 0)
			(size 0 0)
			(layers "B.Cu" "B.Mask" "B.Paste")
			(net "GND")
		)
	)
	(footprint ""
		(layer "B.Cu")
		(at 371.900958 -271.853152 90)
		(property "Reference" "C2249"
			(at 0 0 90)
			(layer "B.SilkS")
			(hide yes)
			(effects
				(font
					(size 1.27 1.27)
				)
				(justify mirror)
			)
		)
		(property "Value" ""
			(at 0 0 90)
			(layer "B.Fab")
			(effects
				(font
					(size 1.27 1.27)
				)
				(justify mirror)
			)
		)
		(duplicate_pad_numbers_are_jumpers no)
		(fp_line
			(start 0.7874 -0.4064)
			(end -0.7874 -0.4064)
			(stroke
				(width 0.1524)
				(type default)
			)
			(layer "B.SilkS")
		)
		(fp_line
			(start -0.7874 -0.4064)
			(end -0.7874 0.4064)
			(stroke
				(width 0.1524)
				(type default)
			)
			(layer "B.SilkS")
		)
		(fp_line
			(start 0.7874 0.4064)
			(end 0.7874 -0.4064)
			(stroke
				(width 0.1524)
				(type default)
			)
			(layer "B.SilkS")
		)
		(fp_line
			(start -0.7874 0.4064)
			(end 0.7874 0.4064)
			(stroke
				(width 0.1524)
				(type default)
			)
			(layer "B.SilkS")
		)
		(fp_line
			(start 0.67945 -0.305054)
			(end 0.12065 -0.305054)
			(stroke
				(width 0.1)
				(type default)
			)
			(layer "B.Fab")
		)
		(fp_line
			(start 0.12065 -0.305054)
			(end 0.12065 -0.2794)
			(stroke
				(width 0.1)
				(type default)
			)
			(layer "B.Fab")
		)
		(fp_line
			(start -0.12065 -0.3048)
			(end -0.67945 -0.3048)
			(stroke
				(width 0.1)
				(type default)
			)
			(layer "B.Fab")
		)
		(fp_line
			(start -0.67945 -0.3048)
			(end -0.67945 0.3048)
			(stroke
				(width 0.1)
				(type default)
			)
			(layer "B.Fab")
		)
		(fp_line
			(start 0.12065 -0.2794)
			(end -0.12065 -0.2794)
			(stroke
				(width 0.1)
				(type default)
			)
			(layer "B.Fab")
		)
		(fp_line
			(start -0.12065 -0.2794)
			(end -0.12065 -0.3048)
			(stroke
				(width 0.1)
				(type default)
			)
			(layer "B.Fab")
		)
		(fp_line
			(start 0.12065 0.2794)
			(end 0.12065 0.3048)
			(stroke
				(width 0.1)
				(type default)
			)
			(layer "B.Fab")
		)
		(fp_line
			(start -0.120396 0.2794)
			(end 0.12065 0.2794)
			(stroke
				(width 0.1)
				(type default)
			)
			(layer "B.Fab")
		)
		(fp_line
			(start 0.67945 0.3048)
			(end 0.67945 -0.305054)
			(stroke
				(width 0.1)
				(type default)
			)
			(layer "B.Fab")
		)
		(fp_line
			(start 0.12065 0.3048)
			(end 0.67945 0.3048)
			(stroke
				(width 0.1)
				(type default)
			)
			(layer "B.Fab")
		)
		(fp_line
			(start -0.120396 0.3048)
			(end -0.120396 0.2794)
			(stroke
				(width 0.1)
				(type default)
			)
			(layer "B.Fab")
		)
		(fp_line
			(start -0.67945 0.3048)
			(end -0.120396 0.3048)
			(stroke
				(width 0.1)
				(type default)
			)
			(layer "B.Fab")
		)
		(pad "1" smd circle
			(at 0.40005 0 270)
			(size 0 0)
			(layers "B.Cu" "B.Mask" "B.Paste")
			(net "PVDDCR_CPU1_P0")
		)
		(pad "2" smd circle
			(at -0.40005 0 270)
			(size 0 0)
			(layers "B.Cu" "B.Mask" "B.Paste")
			(net "GND")
		)
	)
	(footprint ""
		(layer "B.Cu")
		(at 88.306402 -386.766562 90)
		(property "Reference" "C288"
			(at 0 0 90)
			(layer "B.SilkS")
			(hide yes)
			(effects
				(font
					(size 1.27 1.27)
				)
				(justify mirror)
			)
		)
		(property "Value" ""
			(at 0 0 90)
			(layer "B.Fab")
			(effects
				(font
					(size 1.27 1.27)
				)
				(justify mirror)
			)
		)
		(duplicate_pad_numbers_are_jumpers no)
		(fp_line
			(start 0.299974 -0.150114)
			(end -0.299974 -0.150114)
			(stroke
				(width 0.1)
				(type default)
			)
			(layer "B.Fab")
		)
		(fp_line
			(start -0.299974 -0.150114)
			(end -0.299974 0.150114)
			(stroke
				(width 0.1)
				(type default)
			)
			(layer "B.Fab")
		)
		(fp_line
			(start 0.299974 0.150114)
			(end 0.299974 -0.150114)
			(stroke
				(width 0.1)
				(type default)
			)
			(layer "B.Fab")
		)
		(fp_line
			(start -0.299974 0.150114)
			(end 0.299974 0.150114)
			(stroke
				(width 0.1)
				(type default)
			)
			(layer "B.Fab")
		)
		(pad "1" smd rect
			(at 0.2667 0 270)
			(size 0.3048 0.381)
			(layers "B.Cu" "B.Mask" "B.Paste")
			(net "P1V8_CPU1_RT1_1A")
		)
		(pad "2" smd rect
			(at -0.2667 0 270)
			(size 0.3048 0.381)
			(layers "B.Cu" "B.Mask" "B.Paste")
			(net "GND")
		)
	)
)
